(kicad_pcb
	(version 20260206)
	(generator "pcbnew")
	(generator_version "10.0")
	(general
		(thickness 1.6)
		(legacy_teardrops no)
	)
	(paper "A4")
	(title_block
		(title "Bryce Canyon_IOM_IOC_16318-2_OCP.brd")
		(comment 1 "Bryce Canyon / footprints 1529-1536 of 1605")
	)
	(layers
		(0 "F.Cu" signal "TOP")
		(4 "In1.Cu" signal "L2GND")
		(6 "In2.Cu" signal "L3")
		(8 "In3.Cu" signal "L4VCC")
		(10 "In4.Cu" signal "L5VCC")
		(12 "In5.Cu" signal "L6")
		(14 "In6.Cu" signal "L7GND")
		(2 "B.Cu" signal "BOTTOM")
		(9 "F.Adhes" user "F.Adhesive")
		(11 "B.Adhes" user "B.Adhesive")
		(13 "F.Paste" user "Package Geometry/Pastemask Top")
		(15 "B.Paste" user "Package Geometry/Pastemask Bottom")
		(5 "F.SilkS" user "Ref Des/Silkscreen Top")
		(7 "B.SilkS" user "Ref Des/Silkscreen Bottom")
		(1 "F.Mask" user "Board Geometry/Soldermask Top")
		(3 "B.Mask" user "Board Geometry/Soldermask Bottom")
		(17 "Dwgs.User" user "User.Drawings")
		(19 "Cmts.User" user "User.Comments")
		(21 "Eco1.User" user "User.Eco1")
		(23 "Eco2.User" user "User.Eco2")
		(25 "Edge.Cuts" user "Board Geometry/Outline")
		(27 "Margin" user)
		(31 "F.CrtYd" user "Package Geometry/Place Bound Top")
		(29 "B.CrtYd" user "Package Geometry/Place Bound Bottom")
		(35 "F.Fab" user "Ref Des/Assembly Top")
		(33 "B.Fab" user "Ref Des/Assembly Bottom")
	)
	(footprint ""
		(layer "B.Cu")
		(at 167.966136 -38.442138)
		(property "Reference" "C495"
			(at 0 0 0)
			(layer "B.SilkS")
			(hide yes)
			(effects
				(font
					(size 1.27 1.27)
				)
				(justify mirror)
			)
		)
		(property "Value" "SCD01U16V1KX-GP"
			(at 2.8321 -1.7399 0)
			(unlocked yes)
			(layer "B.Fab")
			(hide yes)
			(effects
				(font
					(size 1.016 1.016)
					(thickness 0.1524)
				)
				(justify mirror)
			)
		)
		(property "Device Type" "C0201H13"
			(at 2.8321 -3.2639 0)
			(unlocked yes)
			(layer "B.Fab")
			(hide yes)
			(effects
				(font
					(size 1.016 1.016)
					(thickness 0.1524)
				)
				(justify mirror)
			)
		)
		(duplicate_pad_numbers_are_jumpers no)
		(fp_rect
			(start 0.2794 0.6477)
			(end -0.2794 -0.6477)
			(stroke
				(width 0)
				(type default)
			)
			(fill no)
			(layer "B.CrtYd")
		)
		(fp_rect
			(start 0.2794 0.6477)
			(end -0.2794 -0.6477)
			(stroke
				(width 0)
				(type default)
			)
			(fill no)
			(layer "B.Fab")
		)
		(pad "1" smd custom
			(at 0 -0.2794 180)
			(size 0.0762 0.0762)
			(layers "B.Cu" "B.Mask" "B.Paste")
			(net "PHY_CON_B_TO_IOC_1_DP")
			(options
				(clearance outline)
				(anchor circle)
			)
			(primitives
				(gr_poly
					(pts
						(arc
							(start 0.1524 0.127)
							(mid 0.137521 0.162921)
							(end 0.1016 0.1778)
						)
						(arc
							(start -0.1016 0.1778)
							(mid -0.137521 0.162921)
							(end -0.1524 0.127)
						)
						(arc
							(start -0.1524 -0.127)
							(mid -0.137521 -0.162921)
							(end -0.1016 -0.1778)
						)
						(arc
							(start 0.1016 -0.1778)
							(mid 0.137521 -0.162921)
							(end 0.1524 -0.127)
						)
					)
					(width 0)
					(fill yes)
				)
			)
		)
		(pad "2" smd custom
			(at 0 0.2794 180)
			(size 0.0762 0.0762)
			(layers "B.Cu" "B.Mask" "B.Paste")
			(net "PHY_CON_B_TO_IOC_1_DP_C")
			(options
				(clearance outline)
				(anchor circle)
			)
			(primitives
				(gr_poly
					(pts
						(arc
							(start 0.1524 0.127)
							(mid 0.137521 0.162921)
							(end 0.1016 0.1778)
						)
						(arc
							(start -0.1016 0.1778)
							(mid -0.137521 0.162921)
							(end -0.1524 0.127)
						)
						(arc
							(start -0.1524 -0.127)
							(mid -0.137521 -0.162921)
							(end -0.1016 -0.1778)
						)
						(arc
							(start 0.1016 -0.1778)
							(mid 0.137521 -0.162921)
							(end 0.1524 -0.127)
						)
					)
					(width 0)
					(fill yes)
				)
			)
		)
	)
	(footprint ""
		(layer "B.Cu")
		(at 47.72152 -156.34716 90)
		(property "Reference" "C90"
			(at 0 0 90)
			(layer "B.SilkS")
			(hide yes)
			(effects
				(font
					(size 1.27 1.27)
				)
				(justify mirror)
			)
		)
		(property "Value" "SC1U16V3KX-5GP"
			(at 0 -2.8194 90)
			(unlocked yes)
			(layer "B.Fab")
			(hide yes)
			(effects
				(font
					(size 1.016 1.016)
					(thickness 0.1524)
				)
				(justify mirror)
			)
		)
		(property "Device Type" "C603H36"
			(at 0 -4.3434 90)
			(unlocked yes)
			(layer "B.Fab")
			(hide yes)
			(effects
				(font
					(size 1.016 1.016)
					(thickness 0.1524)
				)
				(justify mirror)
			)
		)
		(duplicate_pad_numbers_are_jumpers no)
		(fp_line
			(start -0.508 0)
			(end 0.508 0)
			(stroke
				(width 0.2032)
				(type default)
			)
			(layer "B.SilkS")
		)
		(fp_rect
			(start 0.5842 1.3335)
			(end -0.5842 -1.3335)
			(stroke
				(width 0)
				(type default)
			)
			(fill no)
			(layer "B.CrtYd")
		)
		(fp_rect
			(start 0.5842 1.3335)
			(end -0.5842 -1.3335)
			(stroke
				(width 0)
				(type default)
			)
			(fill no)
			(layer "B.Fab")
		)
		(pad "1" smd custom
			(at 0 -0.762 270)
			(size 0.2159 0.2159)
			(layers "B.Cu" "B.Mask" "B.Paste")
			(net "DACAV33")
			(options
				(clearance outline)
				(anchor circle)
			)
			(primitives
				(gr_poly
					(pts
						(arc
							(start -0.3302 0.4318)
							(mid -0.402042 0.402042)
							(end -0.4318 0.3302)
						)
						(arc
							(start -0.4318 -0.3302)
							(mid -0.402042 -0.402042)
							(end -0.3302 -0.4318)
						)
						(arc
							(start 0.3302 -0.4318)
							(mid 0.402042 -0.402042)
							(end 0.4318 -0.3302)
						)
						(arc
							(start 0.4318 0.3302)
							(mid 0.402042 0.402042)
							(end 0.3302 0.4318)
						)
					)
					(width 0)
					(fill yes)
				)
			)
		)
		(pad "2" smd custom
			(at 0 0.762 270)
			(size 0.2159 0.2159)
			(layers "B.Cu" "B.Mask" "B.Paste")
			(net "GND")
			(options
				(clearance outline)
				(anchor circle)
			)
			(primitives
				(gr_poly
					(pts
						(arc
							(start -0.3302 0.4318)
							(mid -0.402042 0.402042)
							(end -0.4318 0.3302)
						)
						(arc
							(start -0.4318 -0.3302)
							(mid -0.402042 -0.402042)
							(end -0.3302 -0.4318)
						)
						(arc
							(start 0.3302 -0.4318)
							(mid 0.402042 -0.402042)
							(end 0.4318 -0.3302)
						)
						(arc
							(start 0.4318 0.3302)
							(mid 0.402042 0.402042)
							(end 0.3302 0.4318)
						)
					)
					(width 0)
					(fill yes)
				)
			)
		)
	)
	(footprint ""
		(layer "B.Cu")
		(at 47.73422 -140.208 -90)
		(property "Reference" "C998"
			(at 0 0 90)
			(layer "B.SilkS")
			(hide yes)
			(effects
				(font
					(size 1.27 1.27)
				)
				(justify mirror)
			)
		)
		(property "Value" "SC1U16V3KX-5GP"
			(at 0 -2.8194 270)
			(unlocked yes)
			(layer "B.Fab")
			(hide yes)
			(effects
				(font
					(size 1.016 1.016)
					(thickness 0.1524)
				)
				(justify mirror)
			)
		)
		(property "Device Type" "C603H36"
			(at 0 -4.3434 270)
			(unlocked yes)
			(layer "B.Fab")
			(hide yes)
			(effects
				(font
					(size 1.016 1.016)
					(thickness 0.1524)
				)
				(justify mirror)
			)
		)
		(duplicate_pad_numbers_are_jumpers no)
		(fp_line
			(start -0.508 0)
			(end 0.508 0)
			(stroke
				(width 0.2032)
				(type default)
			)
			(layer "B.SilkS")
		)
		(fp_rect
			(start 0.5842 1.3335)
			(end -0.5842 -1.3335)
			(stroke
				(width 0)
				(type default)
			)
			(fill no)
			(layer "B.CrtYd")
		)
		(fp_rect
			(start 0.5842 1.3335)
			(end -0.5842 -1.3335)
			(stroke
				(width 0)
				(type default)
			)
			(fill no)
			(layer "B.Fab")
		)
		(pad "1" smd custom
			(at 0 -0.762 90)
			(size 0.2159 0.2159)
			(layers "B.Cu" "B.Mask" "B.Paste")
			(net "P1V8_STBY")
			(options
				(clearance outline)
				(anchor circle)
			)
			(primitives
				(gr_poly
					(pts
						(arc
							(start -0.3302 0.4318)
							(mid -0.402042 0.402042)
							(end -0.4318 0.3302)
						)
						(arc
							(start -0.4318 -0.3302)
							(mid -0.402042 -0.402042)
							(end -0.3302 -0.4318)
						)
						(arc
							(start 0.3302 -0.4318)
							(mid 0.402042 -0.402042)
							(end 0.4318 -0.3302)
						)
						(arc
							(start 0.4318 0.3302)
							(mid 0.402042 0.402042)
							(end 0.3302 0.4318)
						)
					)
					(width 0)
					(fill yes)
				)
			)
		)
		(pad "2" smd custom
			(at 0 0.762 90)
			(size 0.2159 0.2159)
			(layers "B.Cu" "B.Mask" "B.Paste")
			(net "GND")
			(options
				(clearance outline)
				(anchor circle)
			)
			(primitives
				(gr_poly
					(pts
						(arc
							(start -0.3302 0.4318)
							(mid -0.402042 0.402042)
							(end -0.4318 0.3302)
						)
						(arc
							(start -0.4318 -0.3302)
							(mid -0.402042 -0.402042)
							(end -0.3302 -0.4318)
						)
						(arc
							(start 0.3302 -0.4318)
							(mid 0.402042 -0.402042)
							(end 0.4318 -0.3302)
						)
						(arc
							(start 0.4318 0.3302)
							(mid 0.402042 0.402042)
							(end 0.3302 0.4318)
						)
					)
					(width 0)
					(fill yes)
				)
			)
		)
	)
	(footprint ""
		(layer "B.Cu")
		(at 91.421966 -159.160718 90)
		(property "Reference" "TP4"
			(at 0 0 90)
			(layer "B.SilkS")
			(hide yes)
			(effects
				(font
					(size 1.27 1.27)
				)
				(justify mirror)
			)
		)
		(property "Value" "TPAD28-2-GP"
			(at 0.0127 -1.6637 90)
			(unlocked yes)
			(layer "B.Fab")
			(hide yes)
			(effects
				(font
					(size 1.016 1.016)
					(thickness 0.1524)
				)
				(justify mirror)
			)
		)
		(property "Device Type" "TPAD28"
			(at 0.0127 -3.1877 90)
			(unlocked yes)
			(layer "B.Fab")
			(hide yes)
			(effects
				(font
					(size 1.016 1.016)
					(thickness 0.1524)
				)
				(justify mirror)
			)
		)
		(duplicate_pad_numbers_are_jumpers no)
		(fp_poly
			(pts
				(arc
					(start 0 0.3556)
					(mid 0 -0.3556)
					(end 0 0.3556)
				)
			)
			(stroke
				(width 0)
				(type default)
			)
			(fill no)
			(layer "B.CrtYd")
		)
		(fp_poly
			(pts
				(arc
					(start 0 0.6096)
					(mid 0 -0.6096)
					(end 0 0.6096)
				)
			)
			(stroke
				(width 0)
				(type default)
			)
			(fill no)
			(layer "B.Fab")
		)
		(pad "1" smd circle
			(at 0 0 270)
			(size 0.7112 0.7112)
			(layers "B.Cu" "B.Mask" "B.Paste")
			(net "PLLFILT")
		)
	)
	(footprint ""
		(layer "B.Cu")
		(at 57.431686 -141.745462 -90)
		(property "Reference" "R175"
			(at 0 0 90)
			(layer "B.SilkS")
			(hide yes)
			(effects
				(font
					(size 1.27 1.27)
				)
				(justify mirror)
			)
		)
		(property "Value" "0R2J-2-GP"
			(at -0.064008 -3.993896 270)
			(unlocked yes)
			(layer "B.Fab")
			(hide yes)
			(effects
				(font
					(size 1.016 1.016)
					(thickness 0.1524)
				)
				(justify mirror)
			)
		)
		(property "Device Type" "R402H16"
			(at -0.064008 -5.517896 270)
			(unlocked yes)
			(layer "B.Fab")
			(hide yes)
			(effects
				(font
					(size 1.016 1.016)
					(thickness 0.1524)
				)
				(justify mirror)
			)
		)
		(duplicate_pad_numbers_are_jumpers no)
		(fp_line
			(start -0.508 -0.9398)
			(end 0.508 -0.9398)
			(stroke
				(width 0.1524)
				(type default)
			)
			(layer "B.SilkS")
		)
		(fp_line
			(start 0.508 -0.9398)
			(end 0.508 0.9398)
			(stroke
				(width 0.1524)
				(type default)
			)
			(layer "B.SilkS")
		)
		(fp_rect
			(start 0.508 0.9398)
			(end -0.508 -0.9398)
			(stroke
				(width 0)
				(type default)
			)
			(fill no)
			(layer "B.CrtYd")
		)
		(fp_rect
			(start 0.508 0.9398)
			(end -0.508 -0.9398)
			(stroke
				(width 0)
				(type default)
			)
			(fill no)
			(layer "B.Fab")
		)
		(pad "1" smd custom
			(at 0 -0.4445 90)
			(size 0.1397 0.1397)
			(layers "B.Cu" "B.Mask" "B.Paste")
			(net "I2C_M2_2_SCL")
			(options
				(clearance outline)
				(anchor circle)
			)
			(primitives
				(gr_poly
					(pts
						(arc
							(start -0.1778 0.2794)
							(mid -0.249642 0.249642)
							(end -0.2794 0.1778)
						)
						(arc
							(start -0.2794 -0.1778)
							(mid -0.249642 -0.249642)
							(end -0.1778 -0.2794)
						)
						(arc
							(start 0.1778 -0.2794)
							(mid 0.249642 -0.249642)
							(end 0.2794 -0.1778)
						)
						(arc
							(start 0.2794 0.1778)
							(mid 0.249642 0.249642)
							(end 0.1778 0.2794)
						)
					)
					(width 0)
					(fill yes)
				)
			)
		)
		(pad "2" smd custom
			(at 0 0.4445 90)
			(size 0.1397 0.1397)
			(layers "B.Cu" "B.Mask" "B.Paste")
			(net "BMC_SMB9_CLK")
			(options
				(clearance outline)
				(anchor circle)
			)
			(primitives
				(gr_poly
					(pts
						(arc
							(start -0.1778 0.2794)
							(mid -0.249642 0.249642)
							(end -0.2794 0.1778)
						)
						(arc
							(start -0.2794 -0.1778)
							(mid -0.249642 -0.249642)
							(end -0.1778 -0.2794)
						)
						(arc
							(start 0.1778 -0.2794)
							(mid 0.249642 -0.249642)
							(end 0.2794 -0.1778)
						)
						(arc
							(start 0.2794 0.1778)
							(mid 0.249642 0.249642)
							(end 0.1778 0.2794)
						)
					)
					(width 0)
					(fill yes)
				)
			)
		)
	)
	(footprint ""
		(layer "B.Cu")
		(at 38.419278 -143.058642)
		(property "Reference" "C58"
			(at 0 0 0)
			(layer "B.SilkS")
			(hide yes)
			(effects
				(font
					(size 1.27 1.27)
				)
				(justify mirror)
			)
		)
		(property "Value" "SC1U16V3KX-5GP"
			(at 0 -2.8194 0)
			(unlocked yes)
			(layer "B.Fab")
			(hide yes)
			(effects
				(font
					(size 1.016 1.016)
					(thickness 0.1524)
				)
				(justify mirror)
			)
		)
		(property "Device Type" "C603H36"
			(at 0 -4.3434 0)
			(unlocked yes)
			(layer "B.Fab")
			(hide yes)
			(effects
				(font
					(size 1.016 1.016)
					(thickness 0.1524)
				)
				(justify mirror)
			)
		)
		(duplicate_pad_numbers_are_jumpers no)
		(fp_line
			(start -0.508 0)
			(end 0.508 0)
			(stroke
				(width 0.2032)
				(type default)
			)
			(layer "B.SilkS")
		)
		(fp_rect
			(start 0.5842 1.3335)
			(end -0.5842 -1.3335)
			(stroke
				(width 0)
				(type default)
			)
			(fill no)
			(layer "B.CrtYd")
		)
		(fp_rect
			(start 0.5842 1.3335)
			(end -0.5842 -1.3335)
			(stroke
				(width 0)
				(type default)
			)
			(fill no)
			(layer "B.Fab")
		)
		(pad "1" smd custom
			(at 0 -0.762 180)
			(size 0.2159 0.2159)
			(layers "B.Cu" "B.Mask" "B.Paste")
			(net "P1V2_STBY")
			(options
				(clearance outline)
				(anchor circle)
			)
			(primitives
				(gr_poly
					(pts
						(arc
							(start -0.3302 0.4318)
							(mid -0.402042 0.402042)
							(end -0.4318 0.3302)
						)
						(arc
							(start -0.4318 -0.3302)
							(mid -0.402042 -0.402042)
							(end -0.3302 -0.4318)
						)
						(arc
							(start 0.3302 -0.4318)
							(mid 0.402042 -0.402042)
							(end 0.4318 -0.3302)
						)
						(arc
							(start 0.4318 0.3302)
							(mid 0.402042 0.402042)
							(end 0.3302 0.4318)
						)
					)
					(width 0)
					(fill yes)
				)
			)
		)
		(pad "2" smd custom
			(at 0 0.762 180)
			(size 0.2159 0.2159)
			(layers "B.Cu" "B.Mask" "B.Paste")
			(net "GND")
			(options
				(clearance outline)
				(anchor circle)
			)
			(primitives
				(gr_poly
					(pts
						(arc
							(start -0.3302 0.4318)
							(mid -0.402042 0.402042)
							(end -0.4318 0.3302)
						)
						(arc
							(start -0.4318 -0.3302)
							(mid -0.402042 -0.402042)
							(end -0.3302 -0.4318)
						)
						(arc
							(start 0.3302 -0.4318)
							(mid 0.402042 -0.402042)
							(end 0.4318 -0.3302)
						)
						(arc
							(start 0.4318 0.3302)
							(mid 0.402042 0.402042)
							(end 0.3302 0.4318)
						)
					)
					(width 0)
					(fill yes)
				)
			)
		)
	)
	(footprint ""
		(layer "B.Cu")
		(at 90.54592 -149.51456)
		(property "Reference" "C14"
			(at 0 0 0)
			(layer "B.SilkS")
			(hide yes)
			(effects
				(font
					(size 1.27 1.27)
				)
				(justify mirror)
			)
		)
		(property "Value" "SC1KP50V2KX-1GP"
			(at -1.1811 -2.7051 0)
			(unlocked yes)
			(layer "B.Fab")
			(hide yes)
			(effects
				(font
					(size 1.016 1.016)
					(thickness 0.1524)
				)
				(justify mirror)
			)
		)
		(property "Device Type" "C402H22"
			(at -1.1811 -4.2291 0)
			(unlocked yes)
			(layer "B.Fab")
			(hide yes)
			(effects
				(font
					(size 1.016 1.016)
					(thickness 0.1524)
				)
				(justify mirror)
			)
		)
		(duplicate_pad_numbers_are_jumpers no)
		(fp_rect
			(start 0.4318 0.9525)
			(end -0.4318 -0.9525)
			(stroke
				(width 0)
				(type default)
			)
			(fill no)
			(layer "B.CrtYd")
		)
		(fp_rect
			(start 0.4318 0.9525)
			(end -0.4318 -0.9525)
			(stroke
				(width 0)
				(type default)
			)
			(fill no)
			(layer "B.Fab")
		)
		(pad "1" smd custom
			(at 0 -0.4445 180)
			(size 0.1524 0.1524)
			(layers "B.Cu" "B.Mask" "B.Paste")
			(net "USB_OCS_N1")
			(options
				(clearance outline)
				(anchor circle)
			)
			(primitives
				(gr_poly
					(pts
						(arc
							(start 0.3048 0.2032)
							(mid 0.275042 0.275042)
							(end 0.2032 0.3048)
						)
						(arc
							(start -0.2032 0.3048)
							(mid -0.275042 0.275042)
							(end -0.3048 0.2032)
						)
						(arc
							(start -0.3048 -0.2032)
							(mid -0.275042 -0.275042)
							(end -0.2032 -0.3048)
						)
						(arc
							(start 0.2032 -0.3048)
							(mid 0.275042 -0.275042)
							(end 0.3048 -0.2032)
						)
					)
					(width 0)
					(fill yes)
				)
			)
		)
		(pad "2" smd custom
			(at 0 0.4445 180)
			(size 0.1524 0.1524)
			(layers "B.Cu" "B.Mask" "B.Paste")
			(net "GND")
			(options
				(clearance outline)
				(anchor circle)
			)
			(primitives
				(gr_poly
					(pts
						(arc
							(start 0.3048 0.2032)
							(mid 0.275042 0.275042)
							(end 0.2032 0.3048)
						)
						(arc
							(start -0.2032 0.3048)
							(mid -0.275042 0.275042)
							(end -0.3048 0.2032)
						)
						(arc
							(start -0.3048 -0.2032)
							(mid -0.275042 -0.275042)
							(end -0.2032 -0.3048)
						)
						(arc
							(start 0.2032 -0.3048)
							(mid 0.275042 -0.275042)
							(end 0.3048 -0.2032)
						)
					)
					(width 0)
					(fill yes)
				)
			)
		)
	)
	(footprint ""
		(layer "B.Cu")
		(at 20.582128 -131.007358 180)
		(property "Reference" "R253"
			(at 0 0 0)
			(layer "B.SilkS")
			(hide yes)
			(effects
				(font
					(size 1.27 1.27)
				)
				(justify mirror)
			)
		)
		(property "Value" "120R2F-GP"
			(at -0.064008 -3.993896 180)
			(unlocked yes)
			(layer "B.Fab")
			(hide yes)
			(effects
				(font
					(size 1.016 1.016)
					(thickness 0.1524)
				)
				(justify mirror)
			)
		)
		(property "Device Type" "R402H16"
			(at -0.064008 -5.517896 180)
			(unlocked yes)
			(layer "B.Fab")
			(hide yes)
			(effects
				(font
					(size 1.016 1.016)
					(thickness 0.1524)
				)
				(justify mirror)
			)
		)
		(duplicate_pad_numbers_are_jumpers no)
		(fp_line
			(start 0.508 -0.9398)
			(end 0.508 0.9398)
			(stroke
				(width 0.1524)
				(type default)
			)
			(layer "B.SilkS")
		)
		(fp_line
			(start -0.508 -0.9398)
			(end 0.508 -0.9398)
			(stroke
				(width 0.1524)
				(type default)
			)
			(layer "B.SilkS")
		)
		(fp_rect
			(start 0.508 0.9398)
			(end -0.508 -0.9398)
			(stroke
				(width 0)
				(type default)
			)
			(fill no)
			(layer "B.CrtYd")
		)
		(fp_rect
			(start 0.508 0.9398)
			(end -0.508 -0.9398)
			(stroke
				(width 0)
				(type default)
			)
			(fill no)
			(layer "B.Fab")
		)
		(pad "1" smd custom
			(at 0 -0.4445)
			(size 0.1397 0.1397)
			(layers "B.Cu" "B.Mask" "B.Paste")
			(net "MEMA_9")
			(options
				(clearance outline)
				(anchor circle)
			)
			(primitives
				(gr_poly
					(pts
						(arc
							(start -0.1778 0.2794)
							(mid -0.249642 0.249642)
							(end -0.2794 0.1778)
						)
						(arc
							(start -0.2794 -0.1778)
							(mid -0.249642 -0.249642)
							(end -0.1778 -0.2794)
						)
						(arc
							(start 0.1778 -0.2794)
							(mid 0.249642 -0.249642)
							(end 0.2794 -0.1778)
						)
						(arc
							(start 0.2794 0.1778)
							(mid 0.249642 0.249642)
							(end 0.1778 0.2794)
						)
					)
					(width 0)
					(fill yes)
				)
			)
		)
		(pad "2" smd custom
			(at 0 0.4445)
			(size 0.1397 0.1397)
			(layers "B.Cu" "B.Mask" "B.Paste")
			(net "P1V2_STBY")
			(options
				(clearance outline)
				(anchor circle)
			)
			(primitives
				(gr_poly
					(pts
						(arc
							(start -0.1778 0.2794)
							(mid -0.249642 0.249642)
							(end -0.2794 0.1778)
						)
						(arc
							(start -0.2794 -0.1778)
							(mid -0.249642 -0.249642)
							(end -0.1778 -0.2794)
						)
						(arc
							(start 0.1778 -0.2794)
							(mid 0.249642 -0.249642)
							(end 0.2794 -0.1778)
						)
						(arc
							(start 0.2794 0.1778)
							(mid 0.249642 0.249642)
							(end 0.1778 0.2794)
						)
					)
					(width 0)
					(fill yes)
				)
			)
		)
	)
)
